# BASEBOARD_FAB2 (Tioga Pass) — schematic netlist excerpt (pin names and nets, part order shuffled) for the footprints in the layout excerpt that follows; sources: Cadence DE-HDL packaged netlist, KiCad conversion of Wiwynn_Tioga_Pass_MB.brd

R9B14  RES  1.00K 1% CHIP  pkg 0402  page 113 : A = PWRGD_CPU0_G ; B = PWRGD_CPU0_G_R
R12W8  4D02R2F-GP  1%  pkg SMD-RG2  page 197 : \1\ = P12V_STBY ; \2\ = P12V_NVDIMM_DEF_D
R7B12  RES  22.1 1.0% CHIP  pkg 0402  page 232 : A = PWRGD_PVPP_DEF_R ; B = PWRGD_PVPP_DEF

(kicad_pcb
	(version 20260206)
	(generator "pcbnew")
	(generator_version "10.0")
	(general
		(thickness 1.6)
		(legacy_teardrops no)
	)
	(paper "A4")
	(title_block
		(title "Wiwynn_Tioga_Pass_MB.brd")
		(comment 1 "Tioga Pass / footprints 1966-1968 of 4770")
	)
	(layers
		(0 "F.Cu" signal "TOP")
		(4 "In1.Cu" signal "L2GND")
		(6 "In2.Cu" signal "L3")
		(8 "In3.Cu" signal "L4GND")
		(10 "In4.Cu" signal "L5")
		(12 "In5.Cu" signal "L6GND")
		(14 "In6.Cu" signal "L7VCC")
		(16 "In7.Cu" signal "L8VCC")
		(18 "In8.Cu" signal "L9GND")
		(20 "In9.Cu" signal "L10")
		(22 "In10.Cu" signal "L11GND")
		(24 "In11.Cu" signal "L12")
		(26 "In12.Cu" signal "L13GND")
		(2 "B.Cu" signal "BOTTOM")
		(9 "F.Adhes" user "F.Adhesive")
		(11 "B.Adhes" user "B.Adhesive")
		(13 "F.Paste" user "Package Geometry/Pastemask Top")
		(15 "B.Paste" user "Package Geometry/Pastemask Bottom")
		(5 "F.SilkS" user "Ref Des/Silkscreen Top")
		(7 "B.SilkS" user "Ref Des/Silkscreen Bottom")
		(1 "F.Mask" user "Board Geometry/Soldermask Top")
		(3 "B.Mask" user "Board Geometry/Soldermask Bottom")
		(17 "Dwgs.User" user "User.Drawings")
		(19 "Cmts.User" user "User.Comments")
		(21 "Eco1.User" user "User.Eco1")
		(23 "Eco2.User" user "User.Eco2")
		(25 "Edge.Cuts" user "Board Geometry/Outline")
		(27 "Margin" user)
		(31 "F.CrtYd" user "Package Geometry/Place Bound Top")
		(29 "B.CrtYd" user "Package Geometry/Place Bound Bottom")
		(35 "F.Fab" user "Ref Des/Assembly Top")
		(33 "B.Fab" user "Ref Des/Assembly Bottom")
	)
	(footprint ""
		(layer "F.Cu")
		(at 353.810062 -128.493266 180)
		(property "Reference" "R7B12"
			(at 0 0 180)
			(layer "F.SilkS")
			(hide yes)
			(effects
				(font
					(size 1.27 1.27)
				)
			)
		)
		(property "Value" ""
			(at 0 0 180)
			(layer "F.Fab")
			(effects
				(font
					(size 1.27 1.27)
				)
			)
		)
		(duplicate_pad_numbers_are_jumpers no)
		(fp_poly
			(pts
				(xy -0.2794 -0.1016) (xy 0.2794 -0.1016) (xy 0.2794 0.9906) (xy -0.2794 0.9906)
			)
			(stroke
				(width 0)
				(type default)
			)
			(fill no)
			(layer "F.CrtYd")
		)
		(fp_line
			(start 0.2794 0.9906)
			(end 0.2794 -0.1016)
			(stroke
				(width 0.1)
				(type default)
			)
			(layer "F.Fab")
		)
		(fp_line
			(start 0.2794 -0.1016)
			(end -0.2794 -0.1016)
			(stroke
				(width 0.1)
				(type default)
			)
			(layer "F.Fab")
		)
		(fp_line
			(start -0.2794 0.9906)
			(end 0.2794 0.9906)
			(stroke
				(width 0.1)
				(type default)
			)
			(layer "F.Fab")
		)
		(fp_line
			(start -0.2794 -0.1016)
			(end -0.2794 0.9906)
			(stroke
				(width 0.1)
				(type default)
			)
			(layer "F.Fab")
		)
		(pad "1" smd rect
			(at 0 0 180)
			(size 0.508 0.508)
			(layers "F.Cu" "F.Mask" "F.Paste")
			(net "PWRGD_PVPP_DEF_R")
		)
		(pad "2" smd rect
			(at 0 0.889 180)
			(size 0.508 0.508)
			(layers "F.Cu" "F.Mask" "F.Paste")
			(net "PWRGD_PVPP_DEF")
		)
		(zone
			(layer "F.Cu")
			(hatch none 0.5)
			(connect_pads
				(clearance 0)
			)
			(min_thickness 0.25)
			(keepout
				(tracks not_allowed)
				(vias allowed)
				(pads allowed)
				(copperpour not_allowed)
				(footprints allowed)
			)
			(placement
				(enabled no)
				(sheetname "")
			)
			(fill
				(thermal_gap 0.5)
				(thermal_bridge_width 0.5)
				(island_removal_mode 0)
			)
			(polygon
				(pts
					(xy 354.064062 -129.128266) (xy 353.556062 -129.128266) (xy 353.556062 -128.747266) (xy 354.064062 -128.747266)
				)
			)
		)
		(zone
			(layer "F.Cu")
			(hatch none 0.5)
			(connect_pads
				(clearance 0)
			)
			(min_thickness 0.25)
			(keepout
				(tracks allowed)
				(vias not_allowed)
				(pads allowed)
				(copperpour not_allowed)
				(footprints allowed)
			)
			(placement
				(enabled no)
				(sheetname "")
			)
			(fill
				(thermal_gap 0.5)
				(thermal_bridge_width 0.5)
				(island_removal_mode 0)
			)
			(polygon
				(pts
					(xy 354.064062 -128.747266) (xy 353.556062 -128.747266) (xy 353.556062 -129.128266) (xy 354.064062 -129.128266)
				)
			)
		)
	)
	(footprint ""
		(layer "F.Cu")
		(at 183.215026 -125.6157 180)
		(property "Reference" "R12W8"
			(at 0 0 180)
			(layer "F.SilkS")
			(hide yes)
			(effects
				(font
					(size 1.27 1.27)
				)
			)
		)
		(property "Value" "*"
			(at 0.064008 -4.108196 180)
			(unlocked yes)
			(layer "F.Fab")
			(hide yes)
			(effects
				(font
					(size 1.27 1.016)
					(thickness 0.1524)
				)
			)
		)
		(property "Device Type" "4D02R2F-GP_SMD-RG2-4D02R2F-GP,A"
			(at 0.064008 -5.632196 180)
			(unlocked yes)
			(layer "F.Fab")
			(hide yes)
			(effects
				(font
					(size 1.27 1.016)
					(thickness 0.1524)
				)
			)
		)
		(duplicate_pad_numbers_are_jumpers no)
		(fp_line
			(start 0.508 -0.9398)
			(end -0.508 -0.9398)
			(stroke
				(width 0.1524)
				(type default)
			)
			(layer "F.SilkS")
		)
		(fp_line
			(start -0.508 -0.9398)
			(end -0.508 0.9398)
			(stroke
				(width 0.1524)
				(type default)
			)
			(layer "F.SilkS")
		)
		(fp_rect
			(start -0.508 0.9398)
			(end 0.508 -0.9398)
			(stroke
				(width 0)
				(type default)
			)
			(fill no)
			(layer "F.CrtYd")
		)
		(fp_rect
			(start -0.508 0.9398)
			(end 0.508 -0.9398)
			(stroke
				(width 0)
				(type default)
			)
			(fill no)
			(layer "F.Fab")
		)
		(pad "1" smd custom
			(at 0 -0.4445 180)
			(size 0.1397 0.1397)
			(layers "F.Cu" "F.Mask" "F.Paste")
			(net "P12V_STBY")
			(options
				(clearance outline)
				(anchor circle)
			)
			(primitives
				(gr_poly
					(pts
						(arc
							(start -0.1778 -0.2794)
							(mid -0.249642 -0.249642)
							(end -0.2794 -0.1778)
						)
						(arc
							(start -0.2794 0.1778)
							(mid -0.249642 0.249642)
							(end -0.1778 0.2794)
						)
						(arc
							(start 0.1778 0.2794)
							(mid 0.249642 0.249642)
							(end 0.2794 0.1778)
						)
						(arc
							(start 0.2794 -0.1778)
							(mid 0.249642 -0.249642)
							(end 0.1778 -0.2794)
						)
					)
					(width 0)
					(fill yes)
				)
			)
		)
		(pad "2" smd custom
			(at 0 0.4445 180)
			(size 0.1397 0.1397)
			(layers "F.Cu" "F.Mask" "F.Paste")
			(net "P12V_NVDIMM_DEF_D")
			(options
				(clearance outline)
				(anchor circle)
			)
			(primitives
				(gr_poly
					(pts
						(arc
							(start -0.1778 -0.2794)
							(mid -0.249642 -0.249642)
							(end -0.2794 -0.1778)
						)
						(arc
							(start -0.2794 0.1778)
							(mid -0.249642 0.249642)
							(end -0.1778 0.2794)
						)
						(arc
							(start 0.1778 0.2794)
							(mid 0.249642 0.249642)
							(end 0.2794 0.1778)
						)
						(arc
							(start 0.2794 -0.1778)
							(mid 0.249642 -0.249642)
							(end 0.1778 -0.2794)
						)
					)
					(width 0)
					(fill yes)
				)
			)
		)
	)
	(footprint ""
		(layer "F.Cu")
		(at 467.0806 -126.6952 180)
		(property "Reference" "R9B14"
			(at 0 0 180)
			(layer "F.SilkS")
			(hide yes)
			(effects
				(font
					(size 1.27 1.27)
				)
			)
		)
		(property "Value" ""
			(at 0 0 180)
			(layer "F.Fab")
			(effects
				(font
					(size 1.27 1.27)
				)
			)
		)
		(duplicate_pad_numbers_are_jumpers no)
		(fp_poly
			(pts
				(xy -0.2794 -0.1016) (xy 0.2794 -0.1016) (xy 0.2794 0.9906) (xy -0.2794 0.9906)
			)
			(stroke
				(width 0)
				(type default)
			)
			(fill no)
			(layer "F.CrtYd")
		)
		(fp_line
			(start 0.2794 0.9906)
			(end 0.2794 -0.1016)
			(stroke
				(width 0.1)
				(type default)
			)
			(layer "F.Fab")
		)
		(fp_line
			(start 0.2794 -0.1016)
			(end -0.2794 -0.1016)
			(stroke
				(width 0.1)
				(type default)
			)
			(layer "F.Fab")
		)
		(fp_line
			(start -0.2794 0.9906)
			(end 0.2794 0.9906)
			(stroke
				(width 0.1)
				(type default)
			)
			(layer "F.Fab")
		)
		(fp_line
			(start -0.2794 -0.1016)
			(end -0.2794 0.9906)
			(stroke
				(width 0.1)
				(type default)
			)
			(layer "F.Fab")
		)
		(pad "1" smd rect
			(at 0 0 180)
			(size 0.508 0.508)
			(layers "F.Cu" "F.Mask" "F.Paste")
			(net "PWRGD_CPU0_G")
		)
		(pad "2" smd rect
			(at 0 0.889 180)
			(size 0.508 0.508)
			(layers "F.Cu" "F.Mask" "F.Paste")
			(net "PWRGD_CPU0_G_R")
		)
		(zone
			(layer "F.Cu")
			(hatch none 0.5)
			(connect_pads
				(clearance 0)
			)
			(min_thickness 0.25)
			(keepout
				(tracks not_allowed)
				(vias allowed)
				(pads allowed)
				(copperpour not_allowed)
				(footprints allowed)
			)
			(placement
				(enabled no)
				(sheetname "")
			)
			(fill
				(thermal_gap 0.5)
				(thermal_bridge_width 0.5)
				(island_removal_mode 0)
			)
			(polygon
				(pts
					(xy 467.3346 -127.3302) (xy 466.8266 -127.3302) (xy 466.8266 -126.9492) (xy 467.3346 -126.9492)
				)
			)
		)
		(zone
			(layer "F.Cu")
			(hatch none 0.5)
			(connect_pads
				(clearance 0)
			)
			(min_thickness 0.25)
			(keepout
				(tracks allowed)
				(vias not_allowed)
				(pads allowed)
				(copperpour not_allowed)
				(footprints allowed)
			)
			(placement
				(enabled no)
				(sheetname "")
			)
			(fill
				(thermal_gap 0.5)
				(thermal_bridge_width 0.5)
				(island_removal_mode 0)
			)
			(polygon
				(pts
					(xy 467.3346 -126.9492) (xy 466.8266 -126.9492) (xy 466.8266 -127.3302) (xy 467.3346 -127.3302)
				)
			)
		)
	)
)
